# BASEBOARD_FAB2 (Tioga Pass) — schematic netlist excerpt (pin names and nets, part order shuffled) for the footprints in the layout excerpt that follows; sources: Cadence DE-HDL packaged netlist, KiCad conversion of Wiwynn_Tioga_Pass_MB.brd

C4G18  CAP  1.0UF 16V 10% X6S  pkg 0402  page 229 : A = VR_PVTT_GHJ_BIAS ; B = GND
R9E23  RES  4.99K 1% CHIP  pkg 0402  page 139 : A = PD_SPRV_RSET ; B = GND
C1F26  CAP  0.220UF 16V 10% X7R  pkg 0402  page 224 : A = VR_PVDDQ_GHJ_PH2_BOOT ; B = VR_PVDDQ_GHJ_PH2_PHASE

(kicad_pcb
	(version 20260206)
	(generator "pcbnew")
	(generator_version "10.0")
	(general
		(thickness 1.6)
		(legacy_teardrops no)
	)
	(paper "A4")
	(title_block
		(title "Wiwynn_Tioga_Pass_MB.brd")
		(comment 1 "Tioga Pass / footprints 1716-1718 of 4770")
	)
	(layers
		(0 "F.Cu" signal "TOP")
		(4 "In1.Cu" signal "L2GND")
		(6 "In2.Cu" signal "L3")
		(8 "In3.Cu" signal "L4GND")
		(10 "In4.Cu" signal "L5")
		(12 "In5.Cu" signal "L6GND")
		(14 "In6.Cu" signal "L7VCC")
		(16 "In7.Cu" signal "L8VCC")
		(18 "In8.Cu" signal "L9GND")
		(20 "In9.Cu" signal "L10")
		(22 "In10.Cu" signal "L11GND")
		(24 "In11.Cu" signal "L12")
		(26 "In12.Cu" signal "L13GND")
		(2 "B.Cu" signal "BOTTOM")
		(9 "F.Adhes" user "F.Adhesive")
		(11 "B.Adhes" user "B.Adhesive")
		(13 "F.Paste" user "Package Geometry/Pastemask Top")
		(15 "B.Paste" user "Package Geometry/Pastemask Bottom")
		(5 "F.SilkS" user "Ref Des/Silkscreen Top")
		(7 "B.SilkS" user "Ref Des/Silkscreen Bottom")
		(1 "F.Mask" user "Board Geometry/Soldermask Top")
		(3 "B.Mask" user "Board Geometry/Soldermask Bottom")
		(17 "Dwgs.User" user "User.Drawings")
		(19 "Cmts.User" user "User.Comments")
		(21 "Eco1.User" user "User.Eco1")
		(23 "Eco2.User" user "User.Eco2")
		(25 "Edge.Cuts" user "Board Geometry/Outline")
		(27 "Margin" user)
		(31 "F.CrtYd" user "Package Geometry/Place Bound Top")
		(29 "B.CrtYd" user "Package Geometry/Place Bound Bottom")
		(35 "F.Fab" user "Ref Des/Assembly Top")
		(33 "B.Fab" user "Ref Des/Assembly Bottom")
	)
	(footprint ""
		(layer "F.Cu")
		(at -0.3302 -19.2151 90)
		(property "Reference" "C1F26"
			(at 0 0 90)
			(layer "F.SilkS")
			(hide yes)
			(effects
				(font
					(size 1.27 1.27)
				)
			)
		)
		(property "Value" ""
			(at 0 0 90)
			(layer "F.Fab")
			(effects
				(font
					(size 1.27 1.27)
				)
			)
		)
		(duplicate_pad_numbers_are_jumpers no)
		(fp_poly
			(pts
				(xy 0.3048 -0.1016) (xy 0.3048 0.9906) (xy -0.3048 0.9906) (xy -0.3048 -0.1016)
			)
			(stroke
				(width 0)
				(type default)
			)
			(fill no)
			(layer "F.CrtYd")
		)
		(fp_line
			(start 0.3048 -0.1016)
			(end -0.3048 -0.1016)
			(stroke
				(width 0.1)
				(type default)
			)
			(layer "F.Fab")
		)
		(fp_line
			(start -0.3048 -0.1016)
			(end -0.3048 0.9906)
			(stroke
				(width 0.1)
				(type default)
			)
			(layer "F.Fab")
		)
		(fp_line
			(start 0.3048 0.9906)
			(end 0.3048 -0.1016)
			(stroke
				(width 0.1)
				(type default)
			)
			(layer "F.Fab")
		)
		(fp_line
			(start -0.3048 0.9906)
			(end 0.3048 0.9906)
			(stroke
				(width 0.1)
				(type default)
			)
			(layer "F.Fab")
		)
		(pad "1" smd rect
			(at 0 0 90)
			(size 0.508 0.508)
			(layers "F.Cu" "F.Mask" "F.Paste")
			(net "VR_PVDDQ_GHJ_PH2_BOOT")
		)
		(pad "2" smd rect
			(at 0 0.889 90)
			(size 0.508 0.508)
			(layers "F.Cu" "F.Mask" "F.Paste")
			(net "VR_PVDDQ_GHJ_PH2_PHASE")
		)
		(zone
			(layer "F.Cu")
			(hatch none 0.5)
			(connect_pads
				(clearance 0)
			)
			(min_thickness 0.25)
			(keepout
				(tracks allowed)
				(vias not_allowed)
				(pads allowed)
				(copperpour not_allowed)
				(footprints allowed)
			)
			(placement
				(enabled no)
				(sheetname "")
			)
			(fill
				(thermal_gap 0.5)
				(thermal_bridge_width 0.5)
				(island_removal_mode 0)
			)
			(polygon
				(pts
					(xy -0.0762 -18.9611) (xy -0.0762 -19.4691) (xy 0.3048 -19.4691) (xy 0.3048 -18.9611)
				)
			)
		)
		(zone
			(layer "F.Cu")
			(hatch none 0.5)
			(connect_pads
				(clearance 0)
			)
			(min_thickness 0.25)
			(keepout
				(tracks not_allowed)
				(vias allowed)
				(pads allowed)
				(copperpour not_allowed)
				(footprints allowed)
			)
			(placement
				(enabled no)
				(sheetname "")
			)
			(fill
				(thermal_gap 0.5)
				(thermal_bridge_width 0.5)
				(island_removal_mode 0)
			)
			(polygon
				(pts
					(xy 0.3048 -18.9611) (xy 0.3048 -19.4691) (xy -0.0762 -19.4691) (xy -0.0762 -18.9611)
				)
			)
		)
	)
	(footprint ""
		(layer "F.Cu")
		(at 173.609 -3.683 90)
		(property "Reference" "C4G18"
			(at 0 0 90)
			(layer "F.SilkS")
			(hide yes)
			(effects
				(font
					(size 1.27 1.27)
				)
			)
		)
		(property "Value" ""
			(at 0 0 90)
			(layer "F.Fab")
			(effects
				(font
					(size 1.27 1.27)
				)
			)
		)
		(duplicate_pad_numbers_are_jumpers no)
		(fp_rect
			(start 0.3048 0.9906)
			(end -0.3048 -0.1016)
			(stroke
				(width 0)
				(type default)
			)
			(fill no)
			(layer "F.CrtYd")
		)
		(fp_line
			(start 0.3048 -0.1016)
			(end -0.3048 -0.1016)
			(stroke
				(width 0.1)
				(type default)
			)
			(layer "F.Fab")
		)
		(fp_line
			(start -0.3048 -0.1016)
			(end -0.3048 0.9906)
			(stroke
				(width 0.1)
				(type default)
			)
			(layer "F.Fab")
		)
		(fp_line
			(start 0.3048 0.9906)
			(end 0.3048 -0.1016)
			(stroke
				(width 0.1)
				(type default)
			)
			(layer "F.Fab")
		)
		(fp_line
			(start -0.3048 0.9906)
			(end 0.3048 0.9906)
			(stroke
				(width 0.1)
				(type default)
			)
			(layer "F.Fab")
		)
		(pad "1" smd rect
			(at 0 0 90)
			(size 0.508 0.508)
			(layers "F.Cu" "F.Mask" "F.Paste")
			(net "VR_PVTT_GHJ_BIAS")
		)
		(pad "2" smd rect
			(at 0 0.889 90)
			(size 0.508 0.508)
			(layers "F.Cu" "F.Mask" "F.Paste")
			(net "GND")
		)
		(zone
			(layer "F.Cu")
			(hatch none 0.5)
			(connect_pads
				(clearance 0)
			)
			(min_thickness 0.25)
			(keepout
				(tracks allowed)
				(vias not_allowed)
				(pads allowed)
				(copperpour not_allowed)
				(footprints allowed)
			)
			(placement
				(enabled no)
				(sheetname "")
			)
			(fill
				(thermal_gap 0.5)
				(thermal_bridge_width 0.5)
				(island_removal_mode 0)
			)
			(polygon
				(pts
					(xy 174.244 -3.937) (xy 173.863 -3.937) (xy 173.863 -3.429) (xy 174.244 -3.429)
				)
			)
		)
		(zone
			(layer "F.Cu")
			(hatch none 0.5)
			(connect_pads
				(clearance 0)
			)
			(min_thickness 0.25)
			(keepout
				(tracks not_allowed)
				(vias allowed)
				(pads allowed)
				(copperpour not_allowed)
				(footprints allowed)
			)
			(placement
				(enabled no)
				(sheetname "")
			)
			(fill
				(thermal_gap 0.5)
				(thermal_bridge_width 0.5)
				(island_removal_mode 0)
			)
			(polygon
				(pts
					(xy 174.244 -3.937) (xy 173.863 -3.937) (xy 173.863 -3.429) (xy 174.244 -3.429)
				)
			)
		)
	)
	(footprint ""
		(layer "F.Cu")
		(at 478.1931 -40.4114 -90)
		(property "Reference" "R9E23"
			(at 0 0 270)
			(layer "F.SilkS")
			(hide yes)
			(effects
				(font
					(size 1.27 1.27)
				)
			)
		)
		(property "Value" ""
			(at 0 0 270)
			(layer "F.Fab")
			(effects
				(font
					(size 1.27 1.27)
				)
			)
		)
		(duplicate_pad_numbers_are_jumpers no)
		(fp_poly
			(pts
				(xy -0.2794 -0.1016) (xy 0.2794 -0.1016) (xy 0.2794 0.9906) (xy -0.2794 0.9906)
			)
			(stroke
				(width 0)
				(type default)
			)
			(fill no)
			(layer "F.CrtYd")
		)
		(fp_line
			(start -0.2794 0.9906)
			(end 0.2794 0.9906)
			(stroke
				(width 0.1)
				(type default)
			)
			(layer "F.Fab")
		)
		(fp_line
			(start 0.2794 0.9906)
			(end 0.2794 -0.1016)
			(stroke
				(width 0.1)
				(type default)
			)
			(layer "F.Fab")
		)
		(fp_line
			(start -0.2794 -0.1016)
			(end -0.2794 0.9906)
			(stroke
				(width 0.1)
				(type default)
			)
			(layer "F.Fab")
		)
		(fp_line
			(start 0.2794 -0.1016)
			(end -0.2794 -0.1016)
			(stroke
				(width 0.1)
				(type default)
			)
			(layer "F.Fab")
		)
		(pad "1" smd rect
			(at 0 0 270)
			(size 0.508 0.508)
			(layers "F.Cu" "F.Mask" "F.Paste")
			(net "PD_SPRV_RSET")
		)
		(pad "2" smd rect
			(at 0 0.889 270)
			(size 0.508 0.508)
			(layers "F.Cu" "F.Mask" "F.Paste")
			(net "GND")
		)
		(zone
			(layer "F.Cu")
			(hatch none 0.5)
			(connect_pads
				(clearance 0)
			)
			(min_thickness 0.25)
			(keepout
				(tracks not_allowed)
				(vias allowed)
				(pads allowed)
				(copperpour not_allowed)
				(footprints allowed)
			)
			(placement
				(enabled no)
				(sheetname "")
			)
			(fill
				(thermal_gap 0.5)
				(thermal_bridge_width 0.5)
				(island_removal_mode 0)
			)
			(polygon
				(pts
					(xy 477.5581 -40.6654) (xy 477.5581 -40.1574) (xy 477.9391 -40.1574) (xy 477.9391 -40.6654)
				)
			)
		)
		(zone
			(layer "F.Cu")
			(hatch none 0.5)
			(connect_pads
				(clearance 0)
			)
			(min_thickness 0.25)
			(keepout
				(tracks allowed)
				(vias not_allowed)
				(pads allowed)
				(copperpour not_allowed)
				(footprints allowed)
			)
			(placement
				(enabled no)
				(sheetname "")
			)
			(fill
				(thermal_gap 0.5)
				(thermal_bridge_width 0.5)
				(island_removal_mode 0)
			)
			(polygon
				(pts
					(xy 477.9391 -40.6654) (xy 477.9391 -40.1574) (xy 477.5581 -40.1574) (xy 477.5581 -40.6654)
				)
			)
		)
	)
)
